# BASEBOARD_FAB2 (Tioga Pass) — schematic netlist excerpt (pin names and nets, part order shuffled) for the footprints in the layout excerpt that follows; sources: Cadence DE-HDL packaged netlist, KiCad conversion of Wiwynn_Tioga_Pass_MB.brd

EU9E1  SPRINGVILLE  IC  pkg SM1  page 139
  LAN_PWR_GOOD  = PU_SPRV_LAN_PWR_GOOD
  NC_SI_CLK_IN  = CLK_50M_CKMNG_SPRVLLE
  NC_SI_CRS_DV  = RMII_BMC_PCH_SPRNGVLLE_CRSDV_R
  JTAG_TDO  = PU_JTAG_SPRV_TDO
  NC_SI_RXD1  = RMII_SPRNGVLLE_BMC_PCH_RXD1_R
  NC_SI_RXD0  = RMII_SPRNGVLLE_BMC_PCH_RXD0_R
  NC_SI_TX_EN  = RMII_BMC_PCH_SPRNGVLLE_TXEN
  NC_SI_TXD1  = RMII_BMC_PCH_SPRNGVLLE_TXD1
  NC_SI_TXD0  = RMII_BMC_PCH_SPRNGVLLE_TXD0
  VDD3P3(4)  = P3V3_STBY
  VDD0P9(2)  = P0V9_LAN
  NVM_SI  = SPI_NIC_MOSI_R
  NVM_SK  = SPI_NIC_SCLK_R
  NVM_SO  = SPI_NIC_MISO
  NVM_CS_N  = SPI_NIC_CS_R_N
  PE_WAKE_N  = FM_PE_SPRV_WAKE_N
  PE_RST_N  = RST_PLTRST_SPRV_R_N
  JTAG_TMS  = PU_JTAG_SPRV_TMS
  JTAG_CLK  = PU_JTAG_SPRV_TCK
  PE_TN  = PE_PCH_SPRV_RX_DN
  PE_TP  = PE_PCH_SPRV_RX_DP
  NC  = NC
  PE_RN  = PE_PCH_SPRV_TX_C_DN
  PE_RP  = PE_PCH_SPRV_TX_C_DP
  PECLKN  = CLK_100M_SPRV_DN
  PECLKP  = CLK_100M_SPRV_DP
  VDD3P3(3)  = P3V3_STBY
  DEV_OFF_N  = PU_DEV_OFF_N
  JTAG_TDI  = PU_JTAG_SPRV_TDI
  LED1  = LED_LAN_1_N
  LED0  = LED_LAN_0_N
  VDD0P9(1)  = P0V9_LAN
  LED2  = LED_LAN_2_N
  SMB_CLK  = SMB_SPRINGVILLE_STBY_LVC3_SCL
  SMB_ALRT_N  = IRQ_LOM_ALERT_N
  SMB_DATA  = SMB_SPRINGVILLE_STBY_LVC3_SDA
  CBOT  = A_CBOT
  VDD0P9_OUT  = P0V9_LAN_I210
  VDD1P5_OUT  = P1V5_LAN
  CTOP  = A_CTOP
  VDD3P3(2)  = P3V3_STBY
  VDD0P9(3)  = P0V9_LAN
  NC_SI_ARB_IN  = RMII_PCH_SPRNGVLLE_ARB_OUT
  NC_SI_ARB_OUT  = RMII_PCH_SPRNGVLLE_ARB_IN_R
  XTAL2  = XTAL_25MHZ_OUT
  XTAL1  = XTAL_25MHZ_IN_R
  VDD1P5(1)  = P1V5_LAN
  RSET  = PD_SPRV_RSET
  MDI_MINUS3_SERN  = NIC_SER_N_MDI_3_DN
  MDI_PLUS3_SERP  = NIC_SER_P_MDI_3_DP
  VDD3P3(1)  = P3V3_STBY_P1V5_LAN_I210
  MDI_MINUS2_SETN  = NIC_SET_N_MDI_2_DN
  MDI_PLUS2_SETP  = NIC_SET_P_MDI_2_DP
  MDI_MINUS1_SRDS_SIG_DET  = NIC_MDI_SPRV_RJ45_1_DN
  MDI_PLUS1_SFP_I2C_CLK  = NIC_MDI_SPRV_RJ45_1_DP
  VDD1P5(0)  = P1V5_LAN_I210
  MDI_MINUS0_SFP_I2C_DATA  = NIC_MDI_SPRV_RJ45_0_DN
  MDI_PLUS0_NC  = NIC_MDI_SPRV_RJ45_0_DP
  VDD0P9(0)  = P0V9_LAN
  SDP3  = TP_SPRV_SDP3
  SDP1_PCIE_DIS_SDP1  = FM_1GB_LOM_DISABLE_N
  SDP2  = TP_SPRV_SDP2
  SDP0  = TP_SPRV_SDP0
  VDD3P3(0)  = P3V3_STBY
  GND  = GND

(kicad_pcb
	(version 20260206)
	(generator "pcbnew")
	(generator_version "10.0")
	(general
		(thickness 1.6)
		(legacy_teardrops no)
	)
	(paper "A4")
	(title_block
		(title "Wiwynn_Tioga_Pass_MB.brd")
		(comment 1 "Tioga Pass / footprint 1033 of 4770 (EU9E1), pads 18-34 of 65")
	)
	(layers
		(0 "F.Cu" signal "TOP")
		(4 "In1.Cu" signal "L2GND")
		(6 "In2.Cu" signal "L3")
		(8 "In3.Cu" signal "L4GND")
		(10 "In4.Cu" signal "L5")
		(12 "In5.Cu" signal "L6GND")
		(14 "In6.Cu" signal "L7VCC")
		(16 "In7.Cu" signal "L8VCC")
		(18 "In8.Cu" signal "L9GND")
		(20 "In9.Cu" signal "L10")
		(22 "In10.Cu" signal "L11GND")
		(24 "In11.Cu" signal "L12")
		(26 "In12.Cu" signal "L13GND")
		(2 "B.Cu" signal "BOTTOM")
		(9 "F.Adhes" user "F.Adhesive")
		(11 "B.Adhes" user "B.Adhesive")
		(13 "F.Paste" user "Package Geometry/Pastemask Top")
		(15 "B.Paste" user "Package Geometry/Pastemask Bottom")
		(5 "F.SilkS" user "Ref Des/Silkscreen Top")
		(7 "B.SilkS" user "Ref Des/Silkscreen Bottom")
		(1 "F.Mask" user "Board Geometry/Soldermask Top")
		(3 "B.Mask" user "Board Geometry/Soldermask Bottom")
		(17 "Dwgs.User" user "User.Drawings")
		(19 "Cmts.User" user "User.Comments")
		(21 "Eco1.User" user "User.Eco1")
		(23 "Eco2.User" user "User.Eco2")
		(25 "Edge.Cuts" user "Board Geometry/Outline")
		(27 "Margin" user)
		(31 "F.CrtYd" user "Package Geometry/Place Bound Top")
		(29 "B.CrtYd" user "Package Geometry/Place Bound Bottom")
		(35 "F.Fab" user "Ref Des/Assembly Top")
		(33 "B.Fab" user "Ref Des/Assembly Bottom")
	)
	(footprint ""
		(layer "F.Cu")
		(at 484.251 -43.9674 180)
		(property "Reference" "EU9E1"
			(at 7.2644 -5.49529 0)
			(unlocked yes)
			(layer "F.SilkS")
			(effects
				(font
					(size 0.7874 0.5842)
					(thickness 0.1524)
				)
				(justify left)
			)
		)
		(property "Value" ""
			(at 0 0 180)
			(layer "F.Fab")
			(effects
				(font
					(size 1.27 1.27)
				)
			)
		)
		(duplicate_pad_numbers_are_jumpers no)
		(pad "18" smd custom
			(at -3.250184 4.3688 180)
			(size 0.0762 0.0762)
			(layers "F.Cu" "F.Mask" "F.Paste")
			(net "PU_JTAG_SPRV_TMS")
			(options
				(clearance outline)
				(anchor circle)
			)
			(primitives
				(gr_poly
					(pts
						(xy -0.1524 0.381)
						(arc
							(start -0.1524 -0.2286)
							(mid 0 -0.381)
							(end 0.1524 -0.2286)
						)
						(xy 0.1524 0.381)
					)
					(width 0)
					(fill yes)
				)
			)
		)
		(pad "19" smd custom
			(at -2.750058 4.3688 180)
			(size 0.0762 0.0762)
			(layers "F.Cu" "F.Mask" "F.Paste")
			(net "PU_JTAG_SPRV_TCK")
			(options
				(clearance outline)
				(anchor circle)
			)
			(primitives
				(gr_poly
					(pts
						(xy -0.1524 0.381)
						(arc
							(start -0.1524 -0.2286)
							(mid 0 -0.381)
							(end 0.1524 -0.2286)
						)
						(xy 0.1524 0.381)
					)
					(width 0)
					(fill yes)
				)
			)
		)
		(pad "20" smd custom
			(at -2.250186 4.3688 180)
			(size 0.0762 0.0762)
			(layers "F.Cu" "F.Mask" "F.Paste")
			(net "PE_PCH_SPRV_RX_DN")
			(options
				(clearance outline)
				(anchor circle)
			)
			(primitives
				(gr_poly
					(pts
						(xy -0.1524 0.381)
						(arc
							(start -0.1524 -0.2286)
							(mid 0 -0.381)
							(end 0.1524 -0.2286)
						)
						(xy 0.1524 0.381)
					)
					(width 0)
					(fill yes)
				)
			)
		)
		(pad "21" smd custom
			(at -1.75006 4.3688 180)
			(size 0.0762 0.0762)
			(layers "F.Cu" "F.Mask" "F.Paste")
			(net "PE_PCH_SPRV_RX_DP")
			(options
				(clearance outline)
				(anchor circle)
			)
			(primitives
				(gr_poly
					(pts
						(xy -0.1524 0.381)
						(arc
							(start -0.1524 -0.2286)
							(mid 0 -0.381)
							(end 0.1524 -0.2286)
						)
						(xy 0.1524 0.381)
					)
					(width 0)
					(fill yes)
				)
			)
		)
		(pad "22" smd custom
			(at -1.250188 4.3688 180)
			(size 0.0762 0.0762)
			(layers "F.Cu" "F.Mask" "F.Paste")
			(net "Net_314")
			(options
				(clearance outline)
				(anchor circle)
			)
			(primitives
				(gr_poly
					(pts
						(xy -0.1524 0.381)
						(arc
							(start -0.1524 -0.2286)
							(mid 0 -0.381)
							(end 0.1524 -0.2286)
						)
						(xy 0.1524 0.381)
					)
					(width 0)
					(fill yes)
				)
			)
		)
		(pad "23" smd custom
			(at -0.750062 4.3688 180)
			(size 0.0762 0.0762)
			(layers "F.Cu" "F.Mask" "F.Paste")
			(net "PE_PCH_SPRV_TX_C_DN")
			(options
				(clearance outline)
				(anchor circle)
			)
			(primitives
				(gr_poly
					(pts
						(xy -0.1524 0.381)
						(arc
							(start -0.1524 -0.2286)
							(mid 0 -0.381)
							(end 0.1524 -0.2286)
						)
						(xy 0.1524 0.381)
					)
					(width 0)
					(fill yes)
				)
			)
		)
		(pad "24" smd custom
			(at -0.25019 4.3688 180)
			(size 0.0762 0.0762)
			(layers "F.Cu" "F.Mask" "F.Paste")
			(net "PE_PCH_SPRV_TX_C_DP")
			(options
				(clearance outline)
				(anchor circle)
			)
			(primitives
				(gr_poly
					(pts
						(xy -0.1524 0.381)
						(arc
							(start -0.1524 -0.2286)
							(mid 0 -0.381)
							(end 0.1524 -0.2286)
						)
						(xy 0.1524 0.381)
					)
					(width 0)
					(fill yes)
				)
			)
		)
		(pad "25" smd custom
			(at 0.249936 4.3688 180)
			(size 0.0762 0.0762)
			(layers "F.Cu" "F.Mask" "F.Paste")
			(net "CLK_100M_SPRV_DN")
			(options
				(clearance outline)
				(anchor circle)
			)
			(primitives
				(gr_poly
					(pts
						(xy -0.1524 0.381)
						(arc
							(start -0.1524 -0.2286)
							(mid 0 -0.381)
							(end 0.1524 -0.2286)
						)
						(xy 0.1524 0.381)
					)
					(width 0)
					(fill yes)
				)
			)
		)
		(pad "26" smd custom
			(at 0.749808 4.3688 180)
			(size 0.0762 0.0762)
			(layers "F.Cu" "F.Mask" "F.Paste")
			(net "CLK_100M_SPRV_DP")
			(options
				(clearance outline)
				(anchor circle)
			)
			(primitives
				(gr_poly
					(pts
						(xy -0.1524 0.381)
						(arc
							(start -0.1524 -0.2286)
							(mid 0 -0.381)
							(end 0.1524 -0.2286)
						)
						(xy 0.1524 0.381)
					)
					(width 0)
					(fill yes)
				)
			)
		)
		(pad "27" smd custom
			(at 1.249934 4.3688 180)
			(size 0.0762 0.0762)
			(layers "F.Cu" "F.Mask" "F.Paste")
			(net "P3V3_STBY")
			(options
				(clearance outline)
				(anchor circle)
			)
			(primitives
				(gr_poly
					(pts
						(xy -0.1524 0.381)
						(arc
							(start -0.1524 -0.2286)
							(mid 0 -0.381)
							(end 0.1524 -0.2286)
						)
						(xy 0.1524 0.381)
					)
					(width 0)
					(fill yes)
				)
			)
		)
		(pad "28" smd custom
			(at 1.749806 4.3688 180)
			(size 0.0762 0.0762)
			(layers "F.Cu" "F.Mask" "F.Paste")
			(net "PU_DEV_OFF_N")
			(options
				(clearance outline)
				(anchor circle)
			)
			(primitives
				(gr_poly
					(pts
						(xy -0.1524 0.381)
						(arc
							(start -0.1524 -0.2286)
							(mid 0 -0.381)
							(end 0.1524 -0.2286)
						)
						(xy 0.1524 0.381)
					)
					(width 0)
					(fill yes)
				)
			)
		)
		(pad "29" smd custom
			(at 2.249932 4.3688 180)
			(size 0.0762 0.0762)
			(layers "F.Cu" "F.Mask" "F.Paste")
			(net "PU_JTAG_SPRV_TDI")
			(options
				(clearance outline)
				(anchor circle)
			)
			(primitives
				(gr_poly
					(pts
						(xy -0.1524 0.381)
						(arc
							(start -0.1524 -0.2286)
							(mid 0 -0.381)
							(end 0.1524 -0.2286)
						)
						(xy 0.1524 0.381)
					)
					(width 0)
					(fill yes)
				)
			)
		)
		(pad "30" smd custom
			(at 2.750058 4.3688 180)
			(size 0.0762 0.0762)
			(layers "F.Cu" "F.Mask" "F.Paste")
			(net "LED_LAN_1_N")
			(options
				(clearance outline)
				(anchor circle)
			)
			(primitives
				(gr_poly
					(pts
						(xy -0.1524 0.381)
						(arc
							(start -0.1524 -0.2286)
							(mid 0 -0.381)
							(end 0.1524 -0.2286)
						)
						(xy 0.1524 0.381)
					)
					(width 0)
					(fill yes)
				)
			)
		)
		(pad "31" smd custom
			(at 3.24993 4.3688 180)
			(size 0.0762 0.0762)
			(layers "F.Cu" "F.Mask" "F.Paste")
			(net "LED_LAN_0_N")
			(options
				(clearance outline)
				(anchor circle)
			)
			(primitives
				(gr_poly
					(pts
						(xy -0.1524 0.381)
						(arc
							(start -0.1524 -0.2286)
							(mid 0 -0.381)
							(end 0.1524 -0.2286)
						)
						(xy 0.1524 0.381)
					)
					(width 0)
					(fill yes)
				)
			)
		)
		(pad "32" smd custom
			(at 3.750056 4.3688 180)
			(size 0.0762 0.0762)
			(layers "F.Cu" "F.Mask" "F.Paste")
			(net "P0V9_LAN")
			(options
				(clearance outline)
				(anchor circle)
			)
			(primitives
				(gr_poly
					(pts
						(xy -0.1524 0.381)
						(arc
							(start -0.1524 -0.2286)
							(mid 0 -0.381)
							(end 0.1524 -0.2286)
						)
						(xy 0.1524 0.381)
					)
					(width 0)
					(fill yes)
				)
			)
		)
		(pad "33" smd custom
			(at 4.3688 3.750056 180)
			(size 0.0762 0.0762)
			(layers "F.Cu" "F.Mask" "F.Paste")
			(net "LED_LAN_2_N")
			(options
				(clearance outline)
				(anchor circle)
			)
			(primitives
				(gr_poly
					(pts
						(xy 0.381 0.1524)
						(arc
							(start -0.2286 0.1524)
							(mid -0.381 0)
							(end -0.2286 -0.1524)
						)
						(xy 0.381 -0.1524)
					)
					(width 0)
					(fill yes)
				)
			)
		)
		(pad "34" smd custom
			(at 4.3688 3.24993 180)
			(size 0.0762 0.0762)
			(layers "F.Cu" "F.Mask" "F.Paste")
			(net "SMB_SPRINGVILLE_STBY_LVC3_SCL")
			(options
				(clearance outline)
				(anchor circle)
			)
			(primitives
				(gr_poly
					(pts
						(xy 0.381 0.1524)
						(arc
							(start -0.2286 0.1524)
							(mid -0.381 0)
							(end -0.2286 -0.1524)
						)
						(xy 0.381 -0.1524)
					)
					(width 0)
					(fill yes)
				)
			)
		)
	)
)
